# BASEBOARD_FAB2 (Tioga Pass) — schematic netlist excerpt (pin names and nets, part order shuffled) for the footprints in the layout excerpt that follows; sources: Cadence DE-HDL packaged netlist, KiCad conversion of Wiwynn_Tioga_Pass_MB.brd

R8G12  RES  0.0 5% EMPTY  pkg 0402  page 189 : A = JTAG_PCH_GBE_TMS ; B = JTAG_TMS
C2D30  CAP_A  22.0UF 4V 20% X6S  pkg 0603V  page 76 : A = PVCCIN_CPU1 ; B = GND

(kicad_pcb
	(version 20260206)
	(generator "pcbnew")
	(generator_version "10.0")
	(general
		(thickness 1.6)
		(legacy_teardrops no)
	)
	(paper "A4")
	(title_block
		(title "Wiwynn_Tioga_Pass_MB.brd")
		(comment 1 "Tioga Pass / footprints 372-373 of 4770")
	)
	(layers
		(0 "F.Cu" signal "TOP")
		(4 "In1.Cu" signal "L2GND")
		(6 "In2.Cu" signal "L3")
		(8 "In3.Cu" signal "L4GND")
		(10 "In4.Cu" signal "L5")
		(12 "In5.Cu" signal "L6GND")
		(14 "In6.Cu" signal "L7VCC")
		(16 "In7.Cu" signal "L8VCC")
		(18 "In8.Cu" signal "L9GND")
		(20 "In9.Cu" signal "L10")
		(22 "In10.Cu" signal "L11GND")
		(24 "In11.Cu" signal "L12")
		(26 "In12.Cu" signal "L13GND")
		(2 "B.Cu" signal "BOTTOM")
		(9 "F.Adhes" user "F.Adhesive")
		(11 "B.Adhes" user "B.Adhesive")
		(13 "F.Paste" user "Package Geometry/Pastemask Top")
		(15 "B.Paste" user "Package Geometry/Pastemask Bottom")
		(5 "F.SilkS" user "Ref Des/Silkscreen Top")
		(7 "B.SilkS" user "Ref Des/Silkscreen Bottom")
		(1 "F.Mask" user "Board Geometry/Soldermask Top")
		(3 "B.Mask" user "Board Geometry/Soldermask Bottom")
		(17 "Dwgs.User" user "User.Drawings")
		(19 "Cmts.User" user "User.Comments")
		(21 "Eco1.User" user "User.Eco1")
		(23 "Eco2.User" user "User.Eco2")
		(25 "Edge.Cuts" user "Board Geometry/Outline")
		(27 "Margin" user)
		(31 "F.CrtYd" user "Package Geometry/Place Bound Top")
		(29 "B.CrtYd" user "Package Geometry/Place Bound Bottom")
		(35 "F.Fab" user "Ref Des/Assembly Top")
		(33 "B.Fab" user "Ref Des/Assembly Bottom")
	)
	(footprint ""
		(layer "F.Cu")
		(at 394.1064 -0.2286)
		(property "Reference" "R8G12"
			(at 0 0 0)
			(layer "F.SilkS")
			(hide yes)
			(effects
				(font
					(size 1.27 1.27)
				)
			)
		)
		(property "Value" ""
			(at 0 0 0)
			(layer "F.Fab")
			(effects
				(font
					(size 1.27 1.27)
				)
			)
		)
		(duplicate_pad_numbers_are_jumpers no)
		(fp_poly
			(pts
				(xy -0.2794 -0.1016) (xy 0.2794 -0.1016) (xy 0.2794 0.9906) (xy -0.2794 0.9906)
			)
			(stroke
				(width 0)
				(type default)
			)
			(fill no)
			(layer "F.CrtYd")
		)
		(fp_line
			(start -0.2794 -0.1016)
			(end -0.2794 0.9906)
			(stroke
				(width 0.1)
				(type default)
			)
			(layer "F.Fab")
		)
		(fp_line
			(start -0.2794 0.9906)
			(end 0.2794 0.9906)
			(stroke
				(width 0.1)
				(type default)
			)
			(layer "F.Fab")
		)
		(fp_line
			(start 0.2794 -0.1016)
			(end -0.2794 -0.1016)
			(stroke
				(width 0.1)
				(type default)
			)
			(layer "F.Fab")
		)
		(fp_line
			(start 0.2794 0.9906)
			(end 0.2794 -0.1016)
			(stroke
				(width 0.1)
				(type default)
			)
			(layer "F.Fab")
		)
		(pad "1" smd rect
			(at 0 0)
			(size 0.508 0.508)
			(layers "F.Cu" "F.Mask" "F.Paste")
			(net "JTAG_PCH_GBE_TMS")
		)
		(pad "2" smd rect
			(at 0 0.889)
			(size 0.508 0.508)
			(layers "F.Cu" "F.Mask" "F.Paste")
			(net "JTAG_TMS")
		)
		(zone
			(layer "F.Cu")
			(hatch none 0.5)
			(connect_pads
				(clearance 0)
			)
			(min_thickness 0.25)
			(keepout
				(tracks allowed)
				(vias not_allowed)
				(pads allowed)
				(copperpour not_allowed)
				(footprints allowed)
			)
			(placement
				(enabled no)
				(sheetname "")
			)
			(fill
				(thermal_gap 0.5)
				(thermal_bridge_width 0.5)
				(island_removal_mode 0)
			)
			(polygon
				(pts
					(xy 393.8524 0.0254) (xy 394.3604 0.0254) (xy 394.3604 0.4064) (xy 393.8524 0.4064)
				)
			)
		)
		(zone
			(layer "F.Cu")
			(hatch none 0.5)
			(connect_pads
				(clearance 0)
			)
			(min_thickness 0.25)
			(keepout
				(tracks not_allowed)
				(vias allowed)
				(pads allowed)
				(copperpour not_allowed)
				(footprints allowed)
			)
			(placement
				(enabled no)
				(sheetname "")
			)
			(fill
				(thermal_gap 0.5)
				(thermal_bridge_width 0.5)
				(island_removal_mode 0)
			)
			(polygon
				(pts
					(xy 393.8524 0.4064) (xy 394.3604 0.4064) (xy 394.3604 0.0254) (xy 393.8524 0.0254)
				)
			)
		)
	)
	(footprint ""
		(layer "F.Cu")
		(at 93.20784 -73.318116)
		(property "Reference" "C2D30"
			(at 0 0 0)
			(layer "F.SilkS")
			(hide yes)
			(effects
				(font
					(size 1.27 1.27)
				)
			)
		)
		(property "Value" ""
			(at 0 0 0)
			(layer "F.Fab")
			(effects
				(font
					(size 1.27 1.27)
				)
			)
		)
		(duplicate_pad_numbers_are_jumpers no)
		(fp_poly
			(pts
				(xy -0.4953 -0.2032) (xy 0.4953 -0.2032) (xy 0.4953 1.6002) (xy -0.4953 1.6002)
			)
			(stroke
				(width 0)
				(type default)
			)
			(fill no)
			(layer "F.CrtYd")
		)
		(fp_line
			(start -0.4953 -0.2032)
			(end 0.4953 -0.2032)
			(stroke
				(width 0.1)
				(type default)
			)
			(layer "F.Fab")
		)
		(fp_line
			(start -0.4953 1.6002)
			(end -0.4953 -0.2032)
			(stroke
				(width 0.1)
				(type default)
			)
			(layer "F.Fab")
		)
		(fp_line
			(start 0.4953 -0.2032)
			(end 0.4953 1.6002)
			(stroke
				(width 0.1)
				(type default)
			)
			(layer "F.Fab")
		)
		(fp_line
			(start 0.4953 1.6002)
			(end -0.4953 1.6002)
			(stroke
				(width 0.1)
				(type default)
			)
			(layer "F.Fab")
		)
		(pad "1" smd rect
			(at 0 0)
			(size 0.762 0.889)
			(layers "F.Cu" "F.Mask" "F.Paste")
			(net "PVCCIN_CPU1")
		)
		(pad "2" smd rect
			(at 0 1.397)
			(size 0.762 0.889)
			(layers "F.Cu" "F.Mask" "F.Paste")
			(net "GND")
		)
		(zone
			(layer "F.Cu")
			(hatch none 0.5)
			(connect_pads
				(clearance 0)
			)
			(min_thickness 0.25)
			(keepout
				(tracks not_allowed)
				(vias allowed)
				(pads allowed)
				(copperpour not_allowed)
				(footprints allowed)
			)
			(placement
				(enabled no)
				(sheetname "")
			)
			(fill
				(thermal_gap 0.5)
				(thermal_bridge_width 0.5)
				(island_removal_mode 0)
			)
			(polygon
				(pts
					(xy 92.82684 -72.873616) (xy 93.58884 -72.873616) (xy 93.58884 -72.365616) (xy 92.82684 -72.365616)
				)
			)
		)
	)
)
